FILE_TYPE=LIBRARY_PARTS;
primitive 'QS3VH257QG8';
  pin
    'S':
      PIN_NUMBER='(1)';
      INPUT_LOAD='(-0.01,0.01)';
    '-E':
      PIN_NUMBER='(15)';
      INPUT_LOAD='(-0.01,0.01)';
    'YA':
      PIN_NUMBER='(4)';
      OUTPUT_LOAD='(1.0,-1.0)';
    'I0A':
      PIN_NUMBER='(2)';
      INPUT_LOAD='(-0.01,0.01)';
    'I1A':
      PIN_NUMBER='(3)';
      INPUT_LOAD='(-0.01,0.01)';
    'I0B':
      PIN_NUMBER='(5)';
      INPUT_LOAD='(-0.01,0.01)';
    'I1B':
      PIN_NUMBER='(6)';
      INPUT_LOAD='(-0.01,0.01)';
    'YB':
      PIN_NUMBER='(7)';
      OUTPUT_LOAD='(1.0,-1.0)';
    'I0C':
      PIN_NUMBER='(11)';
      INPUT_LOAD='(-0.01,0.01)';
    'I1C':
      PIN_NUMBER='(10)';
      INPUT_LOAD='(-0.01,0.01)';
    'YC':
      PIN_NUMBER='(9)';
      OUTPUT_LOAD='(1.0,-1.0)';
    'YD':
      PIN_NUMBER='(12)';
      OUTPUT_LOAD='(1.0,-1.0)';
    'I0D':
      PIN_NUMBER='(14)';
      INPUT_LOAD='(-0.01,0.01)';
    'I1D':
      PIN_NUMBER='(13)';
      INPUT_LOAD='(-0.01,0.01)';
    'GND':
      PIN_NUMBER='(8)';
      PINUSE='POWER';
    'VCC':
      PIN_NUMBER='(16)';
      PINUSE='POWER';
  end_pin;
  body
    PART_NAME='QS3VH257QG8';
    BODY_NAME='QS3VH257QG8';
    JEDEC_TYPE='TSSOP';
    PHYS_DES_PREFIX='U';
    CLASS='IC';
  end_body;
end_primitive;

END.
